(kicad_pcb
	(version 20221018)
	(generator pcbnew)
	(general
    (thickness 1.7403)
  )
	(paper "A4")
	(title_block
    (title "Data Center RDIMM DDR4 Tester")
    (date "2024-09-30")
    (rev "1.2.4")
		(comment 9 "footprint 168 of 690 (U15), pads 439-528 of 676")
	)
	(layers
    (0 "F.Cu" signal)
    (1 "In1.Cu" power)
    (2 "In2.Cu" signal)
    (3 "In3.Cu" power)
    (4 "In4.Cu" power)
    (5 "In5.Cu" signal)
    (6 "In6.Cu" power)
    (7 "In7.Cu" signal)
    (8 "In8.Cu" power)
    (9 "In9.Cu" signal)
    (10 "In10.Cu" power)
    (31 "B.Cu" signal)
    (32 "B.Adhes" user "B.Adhesive")
    (33 "F.Adhes" user "F.Adhesive")
    (34 "B.Paste" user)
    (35 "F.Paste" user)
    (36 "B.SilkS" user "B.Silkscreen")
    (37 "F.SilkS" user "F.Silkscreen")
    (38 "B.Mask" user)
    (39 "F.Mask" user)
    (40 "Dwgs.User" user "User.Drawings")
    (41 "Cmts.User" user "User.Comments")
    (42 "Eco1.User" user "User.Eco1")
    (43 "Eco2.User" user "User.Eco2")
    (44 "Edge.Cuts" user)
    (45 "Margin" user)
    (46 "B.CrtYd" user "B.Courtyard")
    (47 "F.CrtYd" user "F.Courtyard")
    (48 "B.Fab" user)
    (49 "F.Fab" user)
  )
	(footprint "data-center-rdimm-ddr4-tester-footprints:BGA-676_27x27mm_Layout26x26_P1X1mm"
    (layer "F.Cu")
    (at 183.635 90.06 180)
    (descr "FPGA XC7K160TFBG676")
    (tags "FPGA XC7K160TFBG676")
    (property "Author" "Antmicro")
    (property "License" "Apache-2.0")
    (property "MPN" "XC7K160T-FFG676")
    (property "Manufacturer" "AMD-Xilinx")
    (property "Sheetfile" "config-spi.kicad_sch")
    (property "Sheetname" "Config SPI flash")
    (property "ki_description" "Kintex®-7 Field Programmable Gate Array (FPGA) IC 300 4976640 65600 676-BBGA, FCBGA")
    (property "ki_keywords" "SMT, MICROCONTROLLER, IC, FPGA")
    (attr smd)
    (fp_text reference "U15" (at -10.675 -14.7 180) (layer "F.SilkS")
        (effects (font (size 0.7 0.7) (thickness 0.15)) (justify left bottom))
    )
    (fp_text value "XC7K160T-FFG676" (at 0 15.5 180) (layer "F.Fab")
        (effects (font (size 0.7 0.7) (thickness 0.15)) (justify left bottom))
    )
    (pad "L23" smd circle (at 9.499 -2.5 180) (size 0.5 0.5) (layers "F.Cu" "F.Paste" "F.Mask")
      (net 785 "unconnected-(U15C-IO_25_14-PadL23)") (pinfunction "IO_25_14") (pintype "bidirectional+no_connect") (die_length 15.436))
    (pad "L24" smd circle (at 10.499 -2.5 180) (size 0.5 0.5) (layers "F.Cu" "F.Paste" "F.Mask")
      (net 787 "unconnected-(U15B-IO_L8N_T1_13-PadL24)") (pinfunction "IO_L8N_T1_13") (pintype "bidirectional+no_connect") (die_length 16.877))
    (pad "L25" smd circle (at 11.499 -2.5 180) (size 0.5 0.5) (layers "F.Cu" "F.Paste" "F.Mask")
      (net 791 "unconnected-(U15B-IO_L3N_T0_DQS_13-PadL25)") (pinfunction "IO_L3N_T0_DQS_13") (pintype "bidirectional+no_connect") (die_length 16.692))
    (pad "L26" smd circle (at 12.499 -2.5 180) (size 0.5 0.5) (layers "F.Cu" "F.Paste" "F.Mask")
      (net 9 "GND") (pinfunction "GND") (pintype "passive"))
    (pad "M1" smd circle (at -12.5 -1.5 180) (size 0.5 0.5) (layers "F.Cu" "F.Paste" "F.Mask")
      (net 512 "GTX_TX6_N") (pinfunction "MGTXTXN1_115") (pintype "bidirectional") (die_length 13.445))
    (pad "M2" smd circle (at -11.5 -1.5 180) (size 0.5 0.5) (layers "F.Cu" "F.Paste" "F.Mask")
      (net 498 "GTX_TX6_P") (pinfunction "MGTXTXP1_115") (pintype "bidirectional") (die_length 13.639))
    (pad "M3" smd circle (at -10.5 -1.5 180) (size 0.5 0.5) (layers "F.Cu" "F.Paste" "F.Mask")
      (net 306 "1V2_SYS") (pinfunction "MGTAVTT") (pintype "passive"))
    (pad "M4" smd circle (at -9.5 -1.5 180) (size 0.5 0.5) (layers "F.Cu" "F.Paste" "F.Mask")
      (net 9 "GND") (pinfunction "GND") (pintype "passive"))
    (pad "M5" smd circle (at -8.5 -1.5 180) (size 0.5 0.5) (layers "F.Cu" "F.Paste" "F.Mask")
      (net 306 "1V2_SYS") (pinfunction "MGTAVTTRCAL_115") (pintype "power_in"))
    (pad "M6" smd circle (at -7.5 -1.5 180) (size 0.5 0.5) (layers "F.Cu" "F.Paste" "F.Mask")
      (net 663 "Net-(U15J-MGTRREF_115)") (pinfunction "MGTRREF_115") (pintype "power_in") (die_length 11.045))
    (pad "M7" smd circle (at -6.5 -1.5 180) (size 0.5 0.5) (layers "F.Cu" "F.Paste" "F.Mask")
      (net 9 "GND") (pinfunction "GND") (pintype "passive"))
    (pad "M8" smd circle (at -5.5 -1.5 180) (size 0.5 0.5) (layers "F.Cu" "F.Paste" "F.Mask")
      (net 147 "1V0_SYS") (pinfunction "VCCINT") (pintype "passive"))
    (pad "M9" smd circle (at -4.5 -1.5 180) (size 0.5 0.5) (layers "F.Cu" "F.Paste" "F.Mask")
      (net 9 "GND") (pinfunction "GND") (pintype "passive"))
    (pad "M10" smd circle (at -3.5 -1.5 180) (size 0.5 0.5) (layers "F.Cu" "F.Paste" "F.Mask")
      (net 144 "1V8_SYS") (pinfunction "VCCAUX") (pintype "passive"))
    (pad "M11" smd circle (at -2.5 -1.5 180) (size 0.5 0.5) (layers "F.Cu" "F.Paste" "F.Mask")
      (net 9 "GND") (pinfunction "GNDADC_0") (pintype "power_in"))
    (pad "M12" smd circle (at -1.5 -1.5 180) (size 0.5 0.5) (layers "F.Cu" "F.Paste" "F.Mask")
      (net 144 "1V8_SYS") (pinfunction "VCCADC_0") (pintype "power_in"))
    (pad "M13" smd circle (at -0.5 -1.5 180) (size 0.5 0.5) (layers "F.Cu" "F.Paste" "F.Mask")
      (net 9 "GND") (pinfunction "GND") (pintype "passive"))
    (pad "M14" smd circle (at 0.499 -1.5 180) (size 0.5 0.5) (layers "F.Cu" "F.Paste" "F.Mask")
      (net 147 "1V0_SYS") (pinfunction "VCCINT") (pintype "passive"))
    (pad "M15" smd circle (at 1.499 -1.5 180) (size 0.5 0.5) (layers "F.Cu" "F.Paste" "F.Mask")
      (net 9 "GND") (pinfunction "GND") (pintype "passive"))
    (pad "M16" smd circle (at 2.499 -1.5 180) (size 0.5 0.5) (layers "F.Cu" "F.Paste" "F.Mask")
      (net 815 "FMC_IO_25") (pinfunction "IO_25_15") (pintype "bidirectional") (die_length 5.552))
    (pad "M17" smd circle (at 3.499 -1.5 180) (size 0.5 0.5) (layers "F.Cu" "F.Paste" "F.Mask")
      (net 816 "FMC_IO_23_P") (pinfunction "IO_L23P_T3_FOE_B_15") (pintype "bidirectional") (die_length 8.087))
    (pad "M18" smd circle (at 4.499 -1.5 180) (size 0.5 0.5) (layers "F.Cu" "F.Paste" "F.Mask")
      (net 143 "3V3_SYS") (pinfunction "VCCO_15") (pintype "passive"))
    (pad "M19" smd circle (at 5.499 -1.5 180) (size 0.5 0.5) (layers "F.Cu" "F.Paste" "F.Mask")
      (net 792 "unconnected-(U15B-IO_L22N_T3_13-PadM19)") (pinfunction "IO_L22N_T3_13") (pintype "bidirectional+no_connect") (die_length 14.527))
    (pad "M20" smd circle (at 6.499 -1.5 180) (size 0.5 0.5) (layers "F.Cu" "F.Paste" "F.Mask")
      (net 795 "unconnected-(U15B-IO_L7N_T1_13-PadM20)") (pinfunction "IO_L7N_T1_13") (pintype "bidirectional+no_connect") (die_length 12.084))
    (pad "M21" smd circle (at 7.499 -1.5 180) (size 0.5 0.5) (layers "F.Cu" "F.Paste" "F.Mask")
      (net 797 "unconnected-(U15B-IO_L10P_T1_13-PadM21)") (pinfunction "IO_L10P_T1_13") (pintype "bidirectional+no_connect") (die_length 14.496))
    (pad "M22" smd circle (at 8.499 -1.5 180) (size 0.5 0.5) (layers "F.Cu" "F.Paste" "F.Mask")
      (net 801 "unconnected-(U15B-IO_L10N_T1_13-PadM22)") (pinfunction "IO_L10N_T1_13") (pintype "bidirectional+no_connect") (die_length 14.558))
    (pad "M23" smd circle (at 9.499 -1.5 180) (size 0.5 0.5) (layers "F.Cu" "F.Paste" "F.Mask")
      (net 9 "GND") (pinfunction "GND") (pintype "passive"))
    (pad "M24" smd circle (at 10.499 -1.5 180) (size 0.5 0.5) (layers "F.Cu" "F.Paste" "F.Mask")
      (net 802 "unconnected-(U15B-IO_L8P_T1_13-PadM24)") (pinfunction "IO_L8P_T1_13") (pintype "bidirectional+no_connect") (die_length 15.433))
    (pad "M25" smd circle (at 11.499 -1.5 180) (size 0.5 0.5) (layers "F.Cu" "F.Paste" "F.Mask")
      (net 803 "unconnected-(U15B-IO_L3P_T0_DQS_13-PadM25)") (pinfunction "IO_L3P_T0_DQS_13") (pintype "bidirectional+no_connect") (die_length 16.172))
    (pad "M26" smd circle (at 12.499 -1.5 180) (size 0.5 0.5) (layers "F.Cu" "F.Paste" "F.Mask")
      (net 817 "unconnected-(U15B-IO_L5N_T0_13-PadM26)") (pinfunction "IO_L5N_T0_13") (pintype "bidirectional+no_connect") (die_length 16.457))
    (pad "N1" smd circle (at -12.5 -0.5 180) (size 0.5 0.5) (layers "F.Cu" "F.Paste" "F.Mask")
      (net 9 "GND") (pinfunction "GND") (pintype "passive"))
    (pad "N2" smd circle (at -11.5 -0.5 180) (size 0.5 0.5) (layers "F.Cu" "F.Paste" "F.Mask")
      (net 9 "GND") (pinfunction "GND") (pintype "passive"))
    (pad "N3" smd circle (at -10.5 -0.5 180) (size 0.5 0.5) (layers "F.Cu" "F.Paste" "F.Mask")
      (net 648 "GTX_RX6_N") (pinfunction "MGTXRXN1_115") (pintype "bidirectional") (die_length 12.774))
    (pad "N4" smd circle (at -9.5 -0.5 180) (size 0.5 0.5) (layers "F.Cu" "F.Paste" "F.Mask")
      (net 647 "GTX_RX6_P") (pinfunction "MGTXRXP1_115") (pintype "bidirectional") (die_length 12.878))
    (pad "N5" smd circle (at -8.5 -0.5 180) (size 0.5 0.5) (layers "F.Cu" "F.Paste" "F.Mask")
      (net 9 "GND") (pinfunction "GND") (pintype "passive"))
    (pad "N6" smd circle (at -7.5 -0.5 180) (size 0.5 0.5) (layers "F.Cu" "F.Paste" "F.Mask")
      (net 144 "1V8_SYS") (pinfunction "MGTVCCAUX") (pintype "power_in"))
    (pad "N7" smd circle (at -6.5 -0.5 180) (size 0.5 0.5) (layers "F.Cu" "F.Paste" "F.Mask")
      (net 9 "GND") (pinfunction "GND") (pintype "passive"))
    (pad "N8" smd circle (at -5.5 -0.5 180) (size 0.5 0.5) (layers "F.Cu" "F.Paste" "F.Mask")
      (net 13 "TMS_JTAG") (pinfunction "TMS_0") (pintype "bidirectional") (die_length 12.891))
    (pad "N9" smd circle (at -4.5 -0.5 180) (size 0.5 0.5) (layers "F.Cu" "F.Paste" "F.Mask")
      (net 147 "1V0_SYS") (pinfunction "VCCINT") (pintype "passive"))
    (pad "N10" smd circle (at -3.5 -0.5 180) (size 0.5 0.5) (layers "F.Cu" "F.Paste" "F.Mask")
      (net 9 "GND") (pinfunction "GND") (pintype "passive"))
    (pad "N11" smd circle (at -2.5 -0.5 180) (size 0.5 0.5) (layers "F.Cu" "F.Paste" "F.Mask")
      (net 9 "GND") (pinfunction "VREFN_0") (pintype "bidirectional") (die_length 14.753))
    (pad "N12" smd circle (at -1.5 -0.5 180) (size 0.5 0.5) (layers "F.Cu" "F.Paste" "F.Mask")
      (net 9 "GND") (pinfunction "VP_0") (pintype "bidirectional") (die_length 12.915))
    (pad "N13" smd circle (at -0.5 -0.5 180) (size 0.5 0.5) (layers "F.Cu" "F.Paste" "F.Mask")
      (net 147 "1V0_SYS") (pinfunction "VCCBRAM") (pintype "power_in"))
    (pad "N14" smd circle (at 0.499 -0.5 180) (size 0.5 0.5) (layers "F.Cu" "F.Paste" "F.Mask")
      (net 9 "GND") (pinfunction "GND") (pintype "passive"))
    (pad "N15" smd circle (at 1.499 -0.5 180) (size 0.5 0.5) (layers "F.Cu" "F.Paste" "F.Mask")
      (net 147 "1V0_SYS") (pinfunction "VCCINT") (pintype "passive"))
    (pad "N16" smd circle (at 2.499 -0.5 180) (size 0.5 0.5) (layers "F.Cu" "F.Paste" "F.Mask")
      (net 818 "unconnected-(U15B-IO_0_13-PadN16)") (pinfunction "IO_0_13") (pintype "bidirectional+no_connect") (die_length 6.733))
    (pad "N17" smd circle (at 3.499 -0.5 180) (size 0.5 0.5) (layers "F.Cu" "F.Paste" "F.Mask")
      (net 819 "unconnected-(U15B-IO_L20N_T3_13-PadN17)") (pinfunction "IO_L20N_T3_13") (pintype "bidirectional+no_connect") (die_length 9.445))
    (pad "N18" smd circle (at 4.499 -0.5 180) (size 0.5 0.5) (layers "F.Cu" "F.Paste" "F.Mask")
      (net 820 "unconnected-(U15B-IO_L22P_T3_13-PadN18)") (pinfunction "IO_L22P_T3_13") (pintype "bidirectional+no_connect") (die_length 11.191))
    (pad "N19" smd circle (at 5.499 -0.5 180) (size 0.5 0.5) (layers "F.Cu" "F.Paste" "F.Mask")
      (net 821 "unconnected-(U15B-IO_L7P_T1_13-PadN19)") (pinfunction "IO_L7P_T1_13") (pintype "bidirectional+no_connect") (die_length 10.696))
    (pad "N20" smd circle (at 6.499 -0.5 180) (size 0.5 0.5) (layers "F.Cu" "F.Paste" "F.Mask")
      (net 9 "GND") (pinfunction "GND") (pintype "passive"))
    (pad "N21" smd circle (at 7.499 -0.5 180) (size 0.5 0.5) (layers "F.Cu" "F.Paste" "F.Mask")
      (net 822 "unconnected-(U15B-IO_L12P_T1_MRCC_13-PadN21)") (pinfunction "IO_L12P_T1_MRCC_13") (pintype "bidirectional+no_connect") (die_length 11.848))
    (pad "N22" smd circle (at 8.499 -0.5 180) (size 0.5 0.5) (layers "F.Cu" "F.Paste" "F.Mask")
      (net 823 "unconnected-(U15B-IO_L12N_T1_MRCC_13-PadN22)") (pinfunction "IO_L12N_T1_MRCC_13") (pintype "bidirectional+no_connect") (die_length 12.32))
    (pad "N23" smd circle (at 9.499 -0.5 180) (size 0.5 0.5) (layers "F.Cu" "F.Paste" "F.Mask")
      (net 847 "unconnected-(U15B-IO_L11N_T1_SRCC_13-PadN23)") (pinfunction "IO_L11N_T1_SRCC_13") (pintype "bidirectional+no_connect") (die_length 14.434))
    (pad "N24" smd circle (at 10.499 -0.5 180) (size 0.5 0.5) (layers "F.Cu" "F.Paste" "F.Mask")
      (net 848 "unconnected-(U15B-IO_L4N_T0_13-PadN24)") (pinfunction "IO_L4N_T0_13") (pintype "bidirectional+no_connect") (die_length 15.311))
    (pad "N25" smd circle (at 11.499 -0.5 180) (size 0.5 0.5) (layers "F.Cu" "F.Paste" "F.Mask")
      (net 77 "VDDQ") (pinfunction "VCCO_13") (pintype "passive"))
    (pad "N26" smd circle (at 12.499 -0.5 180) (size 0.5 0.5) (layers "F.Cu" "F.Paste" "F.Mask")
      (net 849 "unconnected-(U15B-IO_L5P_T0_13-PadN26)") (pinfunction "IO_L5P_T0_13") (pintype "bidirectional+no_connect") (die_length 16.049))
    (pad "P1" smd circle (at -12.5 0.499 180) (size 0.5 0.5) (layers "F.Cu" "F.Paste" "F.Mask")
      (net 526 "GTX_TX7_N") (pinfunction "MGTXTXN0_115") (pintype "bidirectional") (die_length 14.843))
    (pad "P2" smd circle (at -11.5 0.499 180) (size 0.5 0.5) (layers "F.Cu" "F.Paste" "F.Mask")
      (net 524 "GTX_TX7_P") (pinfunction "MGTXTXP0_115") (pintype "bidirectional") (die_length 15.009))
    (pad "P3" smd circle (at -10.5 0.499 180) (size 0.5 0.5) (layers "F.Cu" "F.Paste" "F.Mask")
      (net 9 "GND") (pinfunction "GND") (pintype "passive"))
    (pad "P4" smd circle (at -9.5 0.499 180) (size 0.5 0.5) (layers "F.Cu" "F.Paste" "F.Mask")
      (net 9 "GND") (pinfunction "GND") (pintype "passive"))
    (pad "P5" smd circle (at -8.5 0.499 180) (size 0.5 0.5) (layers "F.Cu" "F.Paste" "F.Mask")
      (net 18 "MODE2") (pinfunction "M2_0") (pintype "bidirectional") (die_length 16.743))
    (pad "P6" smd circle (at -7.5 0.499 180) (size 0.5 0.5) (layers "F.Cu" "F.Paste" "F.Mask")
      (net 91 "PROGRAM_B") (pinfunction "PROGRAM_B_0") (pintype "bidirectional") (die_length 16.276))
    (pad "P7" smd circle (at -6.5 0.499 180) (size 0.5 0.5) (layers "F.Cu" "F.Paste" "F.Mask")
      (net 100 "CFGBVS") (pinfunction "CFGBVS_0") (pintype "bidirectional") (die_length 14.171))
    (pad "P8" smd circle (at -5.5 0.499 180) (size 0.5 0.5) (layers "F.Cu" "F.Paste" "F.Mask")
      (net 144 "1V8_SYS") (pinfunction "VCCAUX_IO_G0") (pintype "power_in"))
    (pad "P9" smd circle (at -4.5 0.499 180) (size 0.5 0.5) (layers "F.Cu" "F.Paste" "F.Mask")
      (net 9 "GND") (pinfunction "GND") (pintype "passive"))
    (pad "P10" smd circle (at -3.5 0.499 180) (size 0.5 0.5) (layers "F.Cu" "F.Paste" "F.Mask")
      (net 144 "1V8_SYS") (pinfunction "VCCAUX") (pintype "passive"))
    (pad "P11" smd circle (at -2.5 0.499 180) (size 0.5 0.5) (layers "F.Cu" "F.Paste" "F.Mask")
      (net 9 "GND") (pinfunction "VN_0") (pintype "bidirectional") (die_length 13.84))
    (pad "P12" smd circle (at -1.5 0.499 180) (size 0.5 0.5) (layers "F.Cu" "F.Paste" "F.Mask")
      (net 9 "GND") (pinfunction "VREFP_0") (pintype "bidirectional") (die_length 12.633))
    (pad "P13" smd circle (at -0.5 0.499 180) (size 0.5 0.5) (layers "F.Cu" "F.Paste" "F.Mask")
      (net 9 "GND") (pinfunction "GND") (pintype "passive"))
    (pad "P14" smd circle (at 0.499 0.499 180) (size 0.5 0.5) (layers "F.Cu" "F.Paste" "F.Mask")
      (net 147 "1V0_SYS") (pinfunction "VCCINT") (pintype "passive"))
    (pad "P15" smd circle (at 1.499 0.499 180) (size 0.5 0.5) (layers "F.Cu" "F.Paste" "F.Mask")
      (net 9 "GND") (pinfunction "GND") (pintype "passive"))
    (pad "P16" smd circle (at 2.499 0.499 180) (size 0.5 0.5) (layers "F.Cu" "F.Paste" "F.Mask")
      (net 850 "unconnected-(U15B-IO_L20P_T3_13-PadP16)") (pinfunction "IO_L20P_T3_13") (pintype "bidirectional+no_connect") (die_length 8.016))
    (pad "P17" smd circle (at 3.499 0.499 180) (size 0.5 0.5) (layers "F.Cu" "F.Paste" "F.Mask")
      (net 9 "GND") (pinfunction "GND") (pintype "passive"))
    (pad "P18" smd circle (at 4.499 0.499 180) (size 0.5 0.5) (layers "F.Cu" "F.Paste" "F.Mask")
      (net 851 "unconnected-(U15B-IO_L24N_T3_13-PadP18)") (pinfunction "IO_L24N_T3_13") (pintype "bidirectional+no_connect") (die_length 10.217))
    (pad "P19" smd circle (at 5.499 0.499 180) (size 0.5 0.5) (layers "F.Cu" "F.Paste" "F.Mask")
      (net 346 "DQS8_P") (pinfunction "IO_L9P_T1_DQS_13") (pintype "bidirectional") (die_length 12.118))
    (pad "P20" smd circle (at 6.499 0.499 180) (size 0.5 0.5) (layers "F.Cu" "F.Paste" "F.Mask")
      (net 348 "DQS8_N") (pinfunction "IO_L9N_T1_DQS_13") (pintype "bidirectional") (die_length 12.121))
    (pad "P21" smd circle (at 7.499 0.499 180) (size 0.5 0.5) (layers "F.Cu" "F.Paste" "F.Mask")
      (net 852 "unconnected-(U15B-IO_L13N_T2_MRCC_13-PadP21)") (pinfunction "IO_L13N_T2_MRCC_13") (pintype "bidirectional+no_connect") (die_length 10.375))
    (pad "P22" smd circle (at 8.499 0.499 180) (size 0.5 0.5) (layers "F.Cu" "F.Paste" "F.Mask")
      (net 77 "VDDQ") (pinfunction "VCCO_13") (pintype "passive"))
    (pad "P23" smd circle (at 9.499 0.499 180) (size 0.5 0.5) (layers "F.Cu" "F.Paste" "F.Mask")
      (net 858 "unconnected-(U15B-IO_L11P_T1_SRCC_13-PadP23)") (pinfunction "IO_L11P_T1_SRCC_13") (pintype "bidirectional+no_connect") (die_length 14.144))
    (pad "P24" smd circle (at 10.499 0.499 180) (size 0.5 0.5) (layers "F.Cu" "F.Paste" "F.Mask")
      (net 861 "unconnected-(U15B-IO_L4P_T0_13-PadP24)") (pinfunction "IO_L4P_T0_13") (pintype "bidirectional+no_connect") (die_length 13.362))
    (pad "P25" smd circle (at 11.499 0.499 180) (size 0.5 0.5) (layers "F.Cu" "F.Paste" "F.Mask")
      (net 865 "unconnected-(U15B-IO_L6N_T0_VREF_13-PadP25)") (pinfunction "IO_L6N_T0_VREF_13") (pintype "bidirectional+no_connect") (die_length 14.662))
    (pad "P26" smd circle (at 12.499 0.499 180) (size 0.5 0.5) (layers "F.Cu" "F.Paste" "F.Mask")
      (net 866 "unconnected-(U15B-IO_L2N_T0_13-PadP26)") (pinfunction "IO_L2N_T0_13") (pintype "bidirectional+no_connect") (die_length 17.56))
    (pad "R1" smd circle (at -12.5 1.499 180) (size 0.5 0.5) (layers "F.Cu" "F.Paste" "F.Mask")
      (net 9 "GND") (pinfunction "GND") (pintype "passive"))
    (pad "R2" smd circle (at -11.5 1.499 180) (size 0.5 0.5) (layers "F.Cu" "F.Paste" "F.Mask")
      (net 9 "GND") (pinfunction "GND") (pintype "passive"))
    (pad "R3" smd circle (at -10.5 1.499 180) (size 0.5 0.5) (layers "F.Cu" "F.Paste" "F.Mask")
      (net 646 "GTX_RX7_N") (pinfunction "MGTXRXN0_115") (pintype "bidirectional") (die_length 13.691))
    (pad "R4" smd circle (at -9.5 1.499 180) (size 0.5 0.5) (layers "F.Cu" "F.Paste" "F.Mask")
      (net 645 "GTX_RX7_P") (pinfunction "MGTXRXP0_115") (pintype "bidirectional") (die_length 13.771))
    (pad "R5" smd circle (at -8.5 1.499 180) (size 0.5 0.5) (layers "F.Cu" "F.Paste" "F.Mask")
      (net 9 "GND") (pinfunction "GND") (pintype "passive"))
    (pad "R6" smd circle (at -7.5 1.499 180) (size 0.5 0.5) (layers "F.Cu" "F.Paste" "F.Mask")
      (net 14 "TDI_JTAG") (pinfunction "TDI_0") (pintype "bidirectional") (die_length 16.338))
    (pad "R7" smd circle (at -6.5 1.499 180) (size 0.5 0.5) (layers "F.Cu" "F.Paste" "F.Mask")
      (net 15 "TDO_JTAG") (pinfunction "TDO_0") (pintype "bidirectional") (die_length 15.018))
    (pad "R8" smd circle (at -5.5 1.499 180) (size 0.5 0.5) (layers "F.Cu" "F.Paste" "F.Mask")
      (net 9 "GND") (pinfunction "GND") (pintype "passive"))
  )
)
